(kicad_pcb
	(version 20260206)
	(generator "pcbnew")
	(generator_version "10.0")
	(general
		(thickness 1.6)
		(legacy_teardrops no)
	)
	(paper "A4")
	(title_block
		(title "Wiwynn_Tioga_Pass_MB.brd")
		(comment 1 "Tioga Pass / footprint 3283 of 4770 (J6T1), pads 244-291 of 291")
	)
	(layers
		(0 "F.Cu" signal "TOP")
		(4 "In1.Cu" signal "L2GND")
		(6 "In2.Cu" signal "L3")
		(8 "In3.Cu" signal "L4GND")
		(10 "In4.Cu" signal "L5")
		(12 "In5.Cu" signal "L6GND")
		(14 "In6.Cu" signal "L7VCC")
		(16 "In7.Cu" signal "L8VCC")
		(18 "In8.Cu" signal "L9GND")
		(20 "In9.Cu" signal "L10")
		(22 "In10.Cu" signal "L11GND")
		(24 "In11.Cu" signal "L12")
		(26 "In12.Cu" signal "L13GND")
		(2 "B.Cu" signal "BOTTOM")
		(9 "F.Adhes" user "F.Adhesive")
		(11 "B.Adhes" user "B.Adhesive")
		(13 "F.Paste" user "Package Geometry/Pastemask Top")
		(15 "B.Paste" user "Package Geometry/Pastemask Bottom")
		(5 "F.SilkS" user "Ref Des/Silkscreen Top")
		(7 "B.SilkS" user "Ref Des/Silkscreen Bottom")
		(1 "F.Mask" user "Board Geometry/Soldermask Top")
		(3 "B.Mask" user "Board Geometry/Soldermask Bottom")
		(17 "Dwgs.User" user "User.Drawings")
		(19 "Cmts.User" user "User.Comments")
		(21 "Eco1.User" user "User.Eco1")
		(23 "Eco2.User" user "User.Eco2")
		(25 "Edge.Cuts" user "Board Geometry/Outline")
		(27 "Margin" user)
		(31 "F.CrtYd" user "Package Geometry/Place Bound Top")
		(29 "B.CrtYd" user "Package Geometry/Place Bound Bottom")
		(35 "F.Fab" user "Ref Des/Assembly Top")
		(33 "B.Fab" user "Ref Des/Assembly Bottom")
	)
	(footprint ""
		(layer "B.Cu")
		(at 194.700398 -24.824182 90)
		(property "Reference" "J6T1"
			(at 2.200148 39.23411 0)
			(unlocked yes)
			(layer "B.SilkS")
			(effects
				(font
					(size 0.7874 0.5842)
					(thickness 0.1524)
				)
				(justify left mirror)
			)
		)
		(property "Value" ""
			(at 0 0 90)
			(layer "B.Fab")
			(effects
				(font
					(size 1.27 1.27)
				)
				(justify mirror)
			)
		)
		(duplicate_pad_numbers_are_jumpers no)
		(pad "241" smd rect
			(at -4.59994 86.700106 270)
			(size 1.8034 0.508)
			(layers "B.Cu" "B.Mask" "B.Paste")
			(net "GND")
		)
		(pad "242" smd rect
			(at -4.59994 87.54999 270)
			(size 1.8034 0.508)
			(layers "B.Cu" "B.Mask" "B.Paste")
			(net "M_A_DQ<33>")
		)
		(pad "243" smd rect
			(at -4.59994 88.399874 270)
			(size 1.8034 0.508)
			(layers "B.Cu" "B.Mask" "B.Paste")
			(net "GND")
		)
		(pad "244" smd rect
			(at -4.59994 89.250012 270)
			(size 1.8034 0.508)
			(layers "B.Cu" "B.Mask" "B.Paste")
			(net "M_A_DQS_DN<4>")
		)
		(pad "245" smd rect
			(at -4.59994 90.099896 270)
			(size 1.8034 0.508)
			(layers "B.Cu" "B.Mask" "B.Paste")
			(net "M_A_DQS_DP<4>")
		)
		(pad "246" smd rect
			(at -4.59994 90.950034 270)
			(size 1.8034 0.508)
			(layers "B.Cu" "B.Mask" "B.Paste")
			(net "GND")
		)
		(pad "247" smd rect
			(at -4.59994 91.799918 270)
			(size 1.8034 0.508)
			(layers "B.Cu" "B.Mask" "B.Paste")
			(net "M_A_DQ<39>")
		)
		(pad "248" smd rect
			(at -4.59994 92.650056 270)
			(size 1.8034 0.508)
			(layers "B.Cu" "B.Mask" "B.Paste")
			(net "GND")
		)
		(pad "249" smd rect
			(at -4.59994 93.49994 270)
			(size 1.8034 0.508)
			(layers "B.Cu" "B.Mask" "B.Paste")
			(net "M_A_DQ<35>")
		)
		(pad "250" smd rect
			(at -4.59994 94.350078 270)
			(size 1.8034 0.508)
			(layers "B.Cu" "B.Mask" "B.Paste")
			(net "GND")
		)
		(pad "251" smd rect
			(at -4.59994 95.199962 270)
			(size 1.8034 0.508)
			(layers "B.Cu" "B.Mask" "B.Paste")
			(net "M_A_DQ<45>")
		)
		(pad "252" smd rect
			(at -4.59994 96.0501 270)
			(size 1.8034 0.508)
			(layers "B.Cu" "B.Mask" "B.Paste")
			(net "GND")
		)
		(pad "253" smd rect
			(at -4.59994 96.899984 270)
			(size 1.8034 0.508)
			(layers "B.Cu" "B.Mask" "B.Paste")
			(net "M_A_DQ<41>")
		)
		(pad "254" smd rect
			(at -4.59994 97.750122 270)
			(size 1.8034 0.508)
			(layers "B.Cu" "B.Mask" "B.Paste")
			(net "GND")
		)
		(pad "255" smd rect
			(at -4.59994 98.600006 270)
			(size 1.8034 0.508)
			(layers "B.Cu" "B.Mask" "B.Paste")
			(net "M_A_DQS_DN<5>")
		)
		(pad "256" smd rect
			(at -4.59994 99.44989 270)
			(size 1.8034 0.508)
			(layers "B.Cu" "B.Mask" "B.Paste")
			(net "M_A_DQS_DP<5>")
		)
		(pad "257" smd rect
			(at -4.59994 100.300028 270)
			(size 1.8034 0.508)
			(layers "B.Cu" "B.Mask" "B.Paste")
			(net "GND")
		)
		(pad "258" smd rect
			(at -4.59994 101.149912 270)
			(size 1.8034 0.508)
			(layers "B.Cu" "B.Mask" "B.Paste")
			(net "M_A_DQ<47>")
		)
		(pad "259" smd rect
			(at -4.59994 102.00005 270)
			(size 1.8034 0.508)
			(layers "B.Cu" "B.Mask" "B.Paste")
			(net "GND")
		)
		(pad "260" smd rect
			(at -4.59994 102.849934 270)
			(size 1.8034 0.508)
			(layers "B.Cu" "B.Mask" "B.Paste")
			(net "M_A_DQ<43>")
		)
		(pad "261" smd rect
			(at -4.59994 103.700072 270)
			(size 1.8034 0.508)
			(layers "B.Cu" "B.Mask" "B.Paste")
			(net "GND")
		)
		(pad "262" smd rect
			(at -4.59994 104.549956 270)
			(size 1.8034 0.508)
			(layers "B.Cu" "B.Mask" "B.Paste")
			(net "M_A_DQ<53>")
		)
		(pad "263" smd rect
			(at -4.59994 105.400094 270)
			(size 1.8034 0.508)
			(layers "B.Cu" "B.Mask" "B.Paste")
			(net "GND")
		)
		(pad "264" smd rect
			(at -4.59994 106.249978 270)
			(size 1.8034 0.508)
			(layers "B.Cu" "B.Mask" "B.Paste")
			(net "M_A_DQ<49>")
		)
		(pad "265" smd rect
			(at -4.59994 107.100116 270)
			(size 1.8034 0.508)
			(layers "B.Cu" "B.Mask" "B.Paste")
			(net "GND")
		)
		(pad "266" smd rect
			(at -4.59994 107.95 270)
			(size 1.8034 0.508)
			(layers "B.Cu" "B.Mask" "B.Paste")
			(net "M_A_DQS_DN<6>")
		)
		(pad "267" smd rect
			(at -4.59994 108.799884 270)
			(size 1.8034 0.508)
			(layers "B.Cu" "B.Mask" "B.Paste")
			(net "M_A_DQS_DP<6>")
		)
		(pad "268" smd rect
			(at -4.59994 109.650022 270)
			(size 1.8034 0.508)
			(layers "B.Cu" "B.Mask" "B.Paste")
			(net "GND")
		)
		(pad "269" smd rect
			(at -4.59994 110.499906 270)
			(size 1.8034 0.508)
			(layers "B.Cu" "B.Mask" "B.Paste")
			(net "M_A_DQ<55>")
		)
		(pad "270" smd rect
			(at -4.59994 111.350044 270)
			(size 1.8034 0.508)
			(layers "B.Cu" "B.Mask" "B.Paste")
			(net "GND")
		)
		(pad "271" smd rect
			(at -4.59994 112.199928 270)
			(size 1.8034 0.508)
			(layers "B.Cu" "B.Mask" "B.Paste")
			(net "M_A_DQ<51>")
		)
		(pad "272" smd rect
			(at -4.59994 113.050066 270)
			(size 1.8034 0.508)
			(layers "B.Cu" "B.Mask" "B.Paste")
			(net "GND")
		)
		(pad "273" smd rect
			(at -4.59994 113.89995 270)
			(size 1.8034 0.508)
			(layers "B.Cu" "B.Mask" "B.Paste")
			(net "M_A_DQ<61>")
		)
		(pad "274" smd rect
			(at -4.59994 114.750088 270)
			(size 1.8034 0.508)
			(layers "B.Cu" "B.Mask" "B.Paste")
			(net "GND")
		)
		(pad "275" smd rect
			(at -4.59994 115.599972 270)
			(size 1.8034 0.508)
			(layers "B.Cu" "B.Mask" "B.Paste")
			(net "M_A_DQ<57>")
		)
		(pad "276" smd rect
			(at -4.59994 116.45011 270)
			(size 1.8034 0.508)
			(layers "B.Cu" "B.Mask" "B.Paste")
			(net "GND")
		)
		(pad "277" smd rect
			(at -4.59994 117.299994 270)
			(size 1.8034 0.508)
			(layers "B.Cu" "B.Mask" "B.Paste")
			(net "M_A_DQS_DN<7>")
		)
		(pad "278" smd rect
			(at -4.59994 118.149878 270)
			(size 1.8034 0.508)
			(layers "B.Cu" "B.Mask" "B.Paste")
			(net "M_A_DQS_DP<7>")
		)
		(pad "279" smd rect
			(at -4.59994 119.000016 270)
			(size 1.8034 0.508)
			(layers "B.Cu" "B.Mask" "B.Paste")
			(net "GND")
		)
		(pad "280" smd rect
			(at -4.59994 119.8499 270)
			(size 1.8034 0.508)
			(layers "B.Cu" "B.Mask" "B.Paste")
			(net "M_A_DQ<63>")
		)
		(pad "281" smd rect
			(at -4.59994 120.700038 270)
			(size 1.8034 0.508)
			(layers "B.Cu" "B.Mask" "B.Paste")
			(net "GND")
		)
		(pad "282" smd rect
			(at -4.59994 121.549922 270)
			(size 1.8034 0.508)
			(layers "B.Cu" "B.Mask" "B.Paste")
			(net "M_A_DQ<59>")
		)
		(pad "283" smd rect
			(at -4.59994 122.40006 270)
			(size 1.8034 0.508)
			(layers "B.Cu" "B.Mask" "B.Paste")
			(net "GND")
		)
		(pad "284" smd rect
			(at -4.59994 123.249944 270)
			(size 1.8034 0.508)
			(layers "B.Cu" "B.Mask" "B.Paste")
			(net "PVPP_ABC")
		)
		(pad "285" smd rect
			(at -4.59994 124.100082 270)
			(size 1.8034 0.508)
			(layers "B.Cu" "B.Mask" "B.Paste")
			(net "SMB_DDR_ABC_VPP_SDA")
		)
		(pad "286" smd rect
			(at -4.59994 124.949966 270)
			(size 1.8034 0.508)
			(layers "B.Cu" "B.Mask" "B.Paste")
			(net "PVPP_ABC")
		)
		(pad "287" smd rect
			(at -4.59994 125.800104 270)
			(size 1.8034 0.508)
			(layers "B.Cu" "B.Mask" "B.Paste")
			(net "PVPP_ABC")
		)
		(pad "288" smd rect
			(at -4.59994 126.649988 270)
			(size 1.8034 0.508)
			(layers "B.Cu" "B.Mask" "B.Paste")
			(net "PVPP_ABC")
		)
	)
)
